FILE_TYPE = MULTI_PHYS_TABLE;
PART 'CAP'
{========================================================================================}
:VALUE      | VOLTAGE | TOLERANCE  | PACK_TYPE | MATERIAL | PART_NUMBER    = ENVCOMP                            | PART_NUMBER   | JEDEC_TYPE | ALT_SYMBOLS                   | VALUE      | RATED_VOLTAGE | TOL        | CLASS      | DESCRIPTION                                    | HEIGHT     | COMPONENT_TYPE | LEAD_LENGTH | LPID   | SPEED_URL                                                                                                                        | STATUS        | RPL   | AML   | BUS_UNIT          | DAYS  ;
{========================================================================================}
'10.0pF'   | '50V'   | '5%'       | '0402LF'  | 'EMPTY'  | 'A36094-025'(!) = 'YES;YES;YES;UNK;ok;VLD'           | 'A36094-025'  | 'SMC0402A' | '(SMX0402,SMX0402A,SMX0402B)' | 'NA'       | '50V'         | '5%'       | 'DISCRETE' | 'CHIP0402'                                     | '0.024 IN' | 'CHIP0402'     | ''          | '1142' | 'http://speed.intel.com:8081/speed/module/pdm/item/pdm_item_detail_direct.asp?item_cde=A36094-025&item_rev=01&url_param=unused'  | 'Approved'    | 'YES' | '12'  | 'SMO_BOARDS'      | '56' 
'1000pF'   | '50V'   | '10%'      | '0402LF'  | 'X7R'    | 'A36096-046'(!) = 'YES;YES;YES;UNK;ok;CIP'           | 'A36096-046'  | 'SMC0402A' | '(SMX0402,SMX0402A,SMX0402B)' | '1000pF'   | '50V'         | '10%'      | 'DISCRETE' | 'CHIP0402'                                     | '0.024 IN' | 'CHIP0402'     | ''          | '1142' | 'http://speed.intel.com:8081/speed/module/pdm/item/pdm_item_detail_direct.asp?item_cde=A36096-046&item_rev=01&url_param=unused'  | 'Approved'    | 'YES' | '14'  | 'SMO_BOARDS'      | '56' 
'1000pF'   | '50V'   | '10%'      | '0402LF'  | 'EMPTY'  | 'A36096-046'(!) = 'YES;YES;YES;UNK;ok;CIP'           | 'A36096-046'  | 'SMC0402A' | '(SMX0402,SMX0402A,SMX0402B)' | 'NA'       | '50V'         | '10%'      | 'DISCRETE' | 'CHIP0402'                                     | '0.024 IN' | 'CHIP0402'     | ''          | '1142' | 'http://speed.intel.com:8081/speed/module/pdm/item/pdm_item_detail_direct.asp?item_cde=A36096-046&item_rev=01&url_param=unused'  | 'Approved'    | 'YES' | '14'  | 'SMO_BOARDS'      | '56' 
'10.0pF'   | '50V'   | '5%'       | '0402LF'  | 'COG'    | 'A36094-025'(!) = 'YES;YES;YES;UNK;ok;VLD'           | 'A36094-025'  | 'SMC0402A' | '(SMX0402,SMX0402A,SMX0402B)' | '10.0pF'   | '50V'         | '5%'       | 'DISCRETE' | 'CHIP0402'                                     | '0.024 IN' | 'CHIP0402'     | ''          | '1142' | 'http://speed.intel.com:8081/speed/module/pdm/item/pdm_item_detail_direct.asp?item_cde=A36094-025&item_rev=01&url_param=unused'  | 'Approved'    | 'YES' | '12'  | 'SMO_BOARDS'      | '56' 
'1.0uF'    | '6.3V'  | '10%'      | '0402'    | 'X6S'    | 'D97712-004'(!) = 'YES;YES;YES;UNK;ok;VLD'           | 'D97712-004'  | 'SMC0402A' | '(SMX0402,SMX0402A,SMX0402B)' | '1.0uF'    | '6.3V'        | '10%'      | 'DISCRETE' | 'CHIP0402'                                     | '0.022 IN' | 'CHIP0402'     | ''          | '1142' | 'http://speed.intel.com:8081/speed/module/pdm/item/pdm_item_detail_direct.asp?item_cde=D97712-004&item_rev=01&url_param=unused'  | 'Conditional' | 'NO'  | '4'   | 'SMO_BOARDS'      | '???'
'1.0uF'    | '6.3V'  | '10%'      | '0402'    | 'EMPTY'  | 'D97712-004'(!) = 'YES;YES;YES;UNK;ok;VLD'           | 'D97712-004'  | 'SMC0402A' | '(SMX0402,SMX0402A,SMX0402B)' | 'NA'       | '6.3V'        | '10%'      | 'DISCRETE' | 'CHIP0402'                                     | '0.022 IN' | 'CHIP0402'     | ''          | '1142' | 'http://speed.intel.com:8081/speed/module/pdm/item/pdm_item_detail_direct.asp?item_cde=D97712-004&item_rev=01&url_param=unused'  | 'Conditional' | 'NO'  | '4'   | 'SMO_BOARDS'      | '???'
'100.0pF'  | '50V'   | '5%'       | '0402LF'  | 'EMPTY'  | 'A36095-026'(!) = 'YES;YES;YES;UNK;ok;VLD'           | 'A36095-026'  | 'SMC0402A' | '(SMX0402,SMX0402A,SMX0402B)' | 'NA'       | '50V'         | '5%'       | 'DISCRETE' | 'CHIP0402'                                     | '0.024 IN' | 'CHIP0402'     | ''          | '1142' | 'http://speed.intel.com:8081/speed/module/pdm/item/pdm_item_detail_direct.asp?item_cde=A36095-026&item_rev=01&url_param=unused'  | 'Approved'    | 'NO'  | '12'  | 'SMO_BOARDS'      | '56' 
'100.0pF'  | '50V'   | '5%'       | '0402LF'  | 'COG'    | 'A36095-026'(!) = 'YES;YES;YES;UNK;ok;VLD'           | 'A36095-026'  | 'SMC0402A' | '(SMX0402,SMX0402A,SMX0402B)' | '100.0pF'  | '50V'         | '5%'       | 'DISCRETE' | 'CHIP0402'                                     | '0.024 IN' | 'CHIP0402'     | ''          | '1142' | 'http://speed.intel.com:8081/speed/module/pdm/item/pdm_item_detail_direct.asp?item_cde=A36095-026&item_rev=01&url_param=unused'  | 'Approved'    | 'NO'  | '12'  | 'SMO_BOARDS'      | '56' 
'1.0uF'    | '16V'   | '10%'      | '0402'    | 'X7S'    | 'G71842-007'(!) = 'UNK;UNK;UNK;UNK;ok;CIP'           | 'G71842-007'  | 'SMC0402A' | '(SMX0402,SMX0402A,SMX0402B)' | '1.0uF'    | '16V'         | '10%'      | 'DISCRETE' | 'CAPC,X7S,0402,1.00UF,16.00V,+/- 10%'          | '0.024 IN' | 'CHIP0402'     | ''          | '1142' | 'http://speed.intel.com:8081/speed/module/pdm/item/pdm_item_detail_direct.asp?item_cde=G71842-007&item_rev=01&url_param=unused'  | 'Design'      | 'NO'  | '1'   | 'SMO_BOARDS'      | '???'
'1.0uF'    | '16V'   | '10%'      | '0402'    | 'EMPTY'  | 'G71842-007'(!) = 'UNK;UNK;UNK;UNK;ok;CIP'           | 'G71842-007'  | 'SMC0402A' | '(SMX0402,SMX0402A,SMX0402B)' | 'NA'       | '16V'         | '10%'      | 'DISCRETE' | 'CAPC,X7S,0402,1.00UF,16.00V,+/- 10%'          | '0.024 IN' | 'CHIP0402'     | ''          | '1142' | 'http://speed.intel.com:8081/speed/module/pdm/item/pdm_item_detail_direct.asp?item_cde=G71842-007&item_rev=01&url_param=unused'  | 'Design'      | 'NO'  | '1'   | 'SMO_BOARDS'      | '???'
'1.0uF'    | '16V'   | '10%'      | '0402'    | 'X6S'    | 'D97712-011'(!) = ''                                 | 'D97712-011'  | 'SMC0402A' | '(SMX0402,SMX0402A,SMX0402B)' | '1.0uF'    | '16V'         | '10%'      | 'DISCRETE' | 'CAPC,X6S,0402,1.00UF,16.00V,+/- 10%'          | '0.024 IN' | 'CHIP0402'     | ''          | '1142' | 'http://speed.intel.com:8081/speed/module/pdm/item/pdm_item_detail_direct.asp?item_cde=D97712-011&item_rev=01&url_param=unused'  | ''            | ''    | ''    | ''                | ''   
'1.0uF'    | '16V'   | '10%'      | '0402'    | 'EMPTY'  | 'D97712-011'(!) = ''                                 | 'D97712-011'  | 'SMC0402A' | '(SMX0402,SMX0402A,SMX0402B)' | 'NA'       | '16V'         | '10%'      | 'DISCRETE' | 'CAPC,X6S,0402,1.00UF,16.00V,+/- 10%'          | '0.024 IN' | 'CHIP0402'     | ''          | '1142' | 'http://speed.intel.com:8081/speed/module/pdm/item/pdm_item_detail_direct.asp?item_cde=D97712-011&item_rev=01&url_param=unused'  | ''            | ''    | ''    | ''                | ''   
'0.01uF'   | '25V'   | '10%'      | '0402LF'  | 'EMPTY'  | 'A36096-045'(!) = 'YES;YES;YES;UNK;ok;CIP'           | 'A36096-045'  | 'SMC0402A' | '(SMX0402,SMX0402A,SMX0402B)' | 'NA'       | '25V'         | '10%'      | 'DISCRETE' | 'CHIP0402'                                     | '0.024 IN' | 'CHIP0402'     | ''          | '1142' | 'http://speed.intel.com:8081/speed/module/pdm/item/pdm_item_detail_direct.asp?item_cde=A36096-045&item_rev=01&url_param=unused'  | 'Approved'    | 'YES' | '13'  | 'SMO_BOARDS'      | '56' 
'0.01uF'   | '25V'   | '10%'      | '0402LF'  | 'X7R'    | 'A36096-045'(!) = 'YES;YES;YES;UNK;ok;CIP'           | 'A36096-045'  | 'SMC0402A' | '(SMX0402,SMX0402A,SMX0402B)' | '0.01uF'   | '25V'         | '10%'      | 'DISCRETE' | 'CHIP0402'                                     | '0.024 IN' | 'CHIP0402'     | ''          | '1142' | 'http://speed.intel.com:8081/speed/module/pdm/item/pdm_item_detail_direct.asp?item_cde=A36096-045&item_rev=01&url_param=unused'  | 'Approved'    | 'YES' | '13'  | 'SMO_BOARDS'      | '56' 
'0.022uF'  | '16V'   | '10%'      | '0402LF'  | 'X7R'    | 'A36096-073'(!) = 'YES;YES;YES;UNK;ok;VLD'           | 'A36096-073'  | 'SMC0402A' | '(SMX0402,SMX0402A,SMX0402B)' | '0.022uF'  | '16V'         | '10%'      | 'DISCRETE' | 'CHIP0402'                                     | '0.024 IN' | 'CHIP0402'     | ''          | '1142' | 'http://speed.intel.com:8081/speed/module/pdm/item/pdm_item_detail_direct.asp?item_cde=A36096-073&item_rev=01&url_param=unused'  | 'Approved'    | 'NO'  | '8'   | 'SMO_BOARDS'      | '56' 
'0.022uF'  | '16V'   | '10%'      | '0402LF'  | 'EMPTY'  | 'A36096-073'(!) = 'YES;YES;YES;UNK;ok;VLD'           | 'A36096-073'  | 'SMC0402A' | '(SMX0402,SMX0402A,SMX0402B)' | 'NA'       | '16V'         | '10%'      | 'DISCRETE' | 'CHIP0402'                                     | '0.024 IN' | 'CHIP0402'     | ''          | '1142' | 'http://speed.intel.com:8081/speed/module/pdm/item/pdm_item_detail_direct.asp?item_cde=A36096-073&item_rev=01&url_param=unused'  | 'Approved'    | 'NO'  | '8'   | 'SMO_BOARDS'      | '56' 
'0.027uF'  | '16V'   | '10%'      | '0402'    | 'X7R'    | 'A36096-129'(!) = 'UNK;UNK;UNK;UNK;ok;CIP'           | 'A36096-129'  | 'SMC0402A' | '(SMX0402,SMX0402A,SMX0402B)' | '0.027uF'  | '16V'         | '10%'      | 'DISCRETE' | 'CHIP0402'                                     | '0.022 IN' | 'CHIP0402'     | ''          | '1142' | 'http://speed.intel.com:8081/speed/module/pdm/item/pdm_item_detail_direct.asp?item_cde=A36096-129&item_rev=01&url_param=unused'  | 'Design'      | 'YES' | '2'   | 'SMO_BOARDS'      | '???'
'0.027uF'  | '16V'   | '10%'      | '0402'    | 'EMPTY'  | 'A36096-129'(!) = 'UNK;UNK;UNK;UNK;ok;CIP'           | 'A36096-129'  | 'SMC0402A' | '(SMX0402,SMX0402A,SMX0402B)' | 'NA'       | '16V'         | '10%'      | 'DISCRETE' | 'CHIP0402'                                     | '0.022 IN' | 'CHIP0402'     | ''          | '1142' | 'http://speed.intel.com:8081/speed/module/pdm/item/pdm_item_detail_direct.asp?item_cde=A36096-129&item_rev=01&url_param=unused'  | 'Design'      | 'YES' | '2'   | 'SMO_BOARDS'      | '???'
'0.039uF'  | '25V'   | '10%'      | '0402LF'  | 'EMPTY'  | 'A36096-063'(!) = 'YES;YES;YES;UNK;ok;VLD'           | 'A36096-063'  | 'SMC0402A' | '(SMX0402,SMX0402A,SMX0402B)' | 'NA'       | '25V'         | '10%'      | 'DISCRETE' | 'CHIP0402'                                     | '0.024 IN' | 'CHIP0402'     | ''          | '1142' | 'http://speed.intel.com:8081/speed/module/pdm/item/pdm_item_detail_direct.asp?item_cde=A36096-063&item_rev=01&url_param=unused'  | 'Approved'    | 'NO'  | '7'   | 'SMO_BOARDS'      | '56' 
'0.039uF'  | '25V'   | '10%'      | '0402'    | 'EMPTY'  | 'A36096-063'(!) = 'YES;YES;YES;UNK;ok;VLD'           | 'A36096-063'  | 'SMC0402A' | '(SMX0402,SMX0402A,SMX0402B)' | 'NA'       | '25V'         | '10%'      | 'DISCRETE' | 'CHIP0402'                                     | '0.024 IN' | 'CHIP0402'     | ''          | '1142' | 'http://speed.intel.com:8081/speed/module/pdm/item/pdm_item_detail_direct.asp?item_cde=A36096-063&item_rev=01&url_param=unused'  | 'Approved'    | 'NO'  | '7'   | 'SMO_BOARDS'      | '56' 
'0.039uF'  | '25V'   | '10%'      | '0402'    | 'X7R'    | 'A36096-063'(!) = 'YES;YES;YES;UNK;ok;VLD'           | 'A36096-063'  | 'SMC0402A' | '(SMX0402,SMX0402A,SMX0402B)' | '0.039uF'  | '25V'         | '10%'      | 'DISCRETE' | 'CHIP0402'                                     | '0.024 IN' | 'CHIP0402'     | ''          | '1142' | 'http://speed.intel.com:8081/speed/module/pdm/item/pdm_item_detail_direct.asp?item_cde=A36096-063&item_rev=01&url_param=unused'  | 'Approved'    | 'NO'  | '7'   | 'SMO_BOARDS'      | '56' 
'0.039uF'  | '25V'   | '10%'      | '0402LF'  | 'X7R'    | 'A36096-063'(!) = 'YES;YES;YES;UNK;ok;VLD'           | 'A36096-063'  | 'SMC0402A' | '(SMX0402,SMX0402A,SMX0402B)' | '0.039uF'  | '25V'         | '10%'      | 'DISCRETE' | 'CHIP0402'                                     | '0.024 IN' | 'CHIP0402'     | ''          | '1142' | 'http://speed.intel.com:8081/speed/module/pdm/item/pdm_item_detail_direct.asp?item_cde=A36096-063&item_rev=01&url_param=unused'  | 'Approved'    | 'NO'  | '7'   | 'SMO_BOARDS'      | '56' 
'0.047uF'  | '25V'   | '10%'      | '0402'    | 'EMPTY'  | 'A36096-090'(!) = 'YES;YES;YES;UNK;ok;VLD'           | 'A36096-090'  | 'SMC0402A' | '(SMX0402,SMX0402A,SMX0402B)' | 'NA'       | '25V'         | '10%'      | 'DISCRETE' | 'CHIP0402'                                     | '0.020 IN' | 'CHIP0402'     | ''          | '1142' | 'http://speed.intel.com:8081/speed/module/pdm/item/pdm_item_detail_direct.asp?item_cde=A36096-090&item_rev=01&url_param=unused'  | 'Conditional' | 'YES' | '5'   | 'SMO_BOARDS'      | '14' 
'0.047uF'  | '25V'   | '10%'      | '0402'    | 'X7R'    | 'A36096-090'(!) = 'YES;YES;YES;UNK;ok;VLD'           | 'A36096-090'  | 'SMC0402A' | '(SMX0402,SMX0402A,SMX0402B)' | '0.047uF'  | '25V'         | '10%'      | 'DISCRETE' | 'CHIP0402'                                     | '0.020 IN' | 'CHIP0402'     | ''          | '1142' | 'http://speed.intel.com:8081/speed/module/pdm/item/pdm_item_detail_direct.asp?item_cde=A36096-090&item_rev=01&url_param=unused'  | 'Conditional' | 'YES' | '5'   | 'SMO_BOARDS'      | '14' 
'0.1uF'    | '16V'   | '10%'      | '0402'    | 'EMPTY'  | 'A36096-030'(!) = 'YES;YES;YES;UNK;ok;VLD'           | 'A36096-030'  | 'SMC0402A' | '(SMX0402,SMX0402A,SMX0402B)' | 'NA'       | '16V'         | '10%'      | 'DISCRETE' | 'CHIP0402'                                     | '0.024 IN' | 'CHIP0402'     | ''          | '1142' | 'http://speed.intel.com:8081/speed/module/pdm/item/pdm_item_detail_direct.asp?item_cde=A36096-030&item_rev=01&url_param=unused'  | 'Approved'    | 'YES' | '12'  | 'SMO_BOARDS'      | '56' 
'0.1uF'    | '16V'   | '10%'      | '0402LF'  | 'EMPTY'  | 'A36096-030'(!) = 'YES;YES;YES;UNK;ok;VLD'           | 'A36096-030'  | 'SMC0402A' | '(SMX0402,SMX0402A,SMX0402B)' | 'NA'       | '16V'         | '10%'      | 'DISCRETE' | 'CHIP0402'                                     | '0.024 IN' | 'CHIP0402'     | ''          | '1142' | 'http://speed.intel.com:8081/speed/module/pdm/item/pdm_item_detail_direct.asp?item_cde=A36096-030&item_rev=01&url_param=unused'  | 'Approved'    | 'YES' | '12'  | 'SMO_BOARDS'      | '56' 
'0.1uF'    | '16V'   | '10%'      | '0402LF'  | 'X7R'    | 'A36096-030'(!) = 'YES;YES;YES;UNK;ok;VLD'           | 'A36096-030'  | 'SMC0402A' | '(SMX0402,SMX0402A,SMX0402B)' | '0.1uF'    | '16V'         | '10%'      | 'DISCRETE' | 'CHIP0402'                                     | '0.024 IN' | 'CHIP0402'     | ''          | '1142' | 'http://speed.intel.com:8081/speed/module/pdm/item/pdm_item_detail_direct.asp?item_cde=A36096-030&item_rev=01&url_param=unused'  | 'Approved'    | 'YES' | '12'  | 'SMO_BOARDS'      | '56' 
'0.1uF'    | '16V'   | '10%'      | '0402'    | 'X7R'    | 'A36096-030'(!) = 'YES;YES;YES;UNK;ok;VLD'           | 'A36096-030'  | 'SMC0402A' | '(SMX0402,SMX0402A,SMX0402B)' | '0.1uF'    | '16V'         | '10%'      | 'DISCRETE' | 'CHIP0402'                                     | '0.024 IN' | 'CHIP0402'     | ''          | '1142' | 'http://speed.intel.com:8081/speed/module/pdm/item/pdm_item_detail_direct.asp?item_cde=A36096-030&item_rev=01&url_param=unused'  | 'Approved'    | 'YES' | '12'  | 'SMO_BOARDS'      | '56' 
'0.220uF'  | '16V'   | '10%'      | '0402'    | 'X7R'    | 'A36096-104'(!) = 'YES;YES;YES;UNK;ok;VLD'           | 'A36096-104'  | 'SMC0402A' | '(SMX0402,SMX0402A,SMX0402B)' | '0.220uF'  | '16V'         | '10%'      | 'DISCRETE' | 'CHIP0402'                                     | '0.022 IN' | 'CHIP0402'     | ''          | '1142' | 'http://speed.intel.com:8081/speed/module/pdm/item/pdm_item_detail_direct.asp?item_cde=A36096-104&item_rev=01&url_param=unused'  | 'Conditional' | 'YES' | '3'   | 'SMO_BOARDS'      | '56' 
'0.22uF'   | '16V'   | '10%'      | '0402'    | 'EMPTY'  | 'A36096-155'(!) = ''                                 | 'A36096-155'  | 'SMC0402A' | '(SMX0402,SMX0402A,SMX0402B)' | 'NA'       | '16V'         | '10%'      | 'DISCRETE' | 'CAPC,X7R,0402,0.22UF,16.00V,+/- 10%'          | '0.022 IN' | 'CHIP0402'     | ''          | '1142' | 'http://speed.intel.com:8081/speed/module/pdm/item/pdm_item_detail_direct.asp?item_cde=A36096-155&item_rev=01&url_param=unused'  | ''            | ''    | ''    | ''                | ''   
'0.220uF'  | '16V'   | '10%'      | '0402'    | 'EMPTY'  | 'A36096-104'(!) = 'YES;YES;YES;UNK;ok;VLD'           | 'A36096-104'  | 'SMC0402A' | '(SMX0402,SMX0402A,SMX0402B)' | 'NA'       | '16V'         | '10%'      | 'DISCRETE' | 'CHIP0402'                                     | '0.022 IN' | 'CHIP0402'     | ''          | '1142' | 'http://speed.intel.com:8081/speed/module/pdm/item/pdm_item_detail_direct.asp?item_cde=A36096-104&item_rev=01&url_param=unused'  | 'Conditional' | 'YES' | '3'   | 'SMO_BOARDS'      | '56' 
'0.22uF'   | '16V'   | '10%'      | '0402'    | 'X7R'    | 'A36096-155'(!) = ''                                 | 'A36096-155'  | 'SMC0402A' | '(SMX0402,SMX0402A,SMX0402B)' | '0.22uF'   | '16V'         | '10%'      | 'DISCRETE' | 'CAPC,X7R,0402,0.22UF,16.00V,+/- 10%'          | '0.022 IN' | 'CHIP0402'     | ''          | '1142' | 'http://speed.intel.com:8081/speed/module/pdm/item/pdm_item_detail_direct.asp?item_cde=A36096-155&item_rev=01&url_param=unused'  | ''            | ''    | ''    | ''                | ''   
'12.0pF'   | '50V'   | '5%'       | '0402LF'  | 'COG'    | 'A36095-043'(!) = 'YES;YES;YES;UNK;ok;VLD'           | 'A36095-043'  | 'SMC0402A' | '(SMX0402,SMX0402A,SMX0402B)' | '12.0pF'   | '50V'         | '5%'       | 'DISCRETE' | 'CHIP0402'                                     | '0.024 IN' | 'CHIP0402'     | ''          | '1142' | 'http://speed.intel.com:8081/speed/module/pdm/item/pdm_item_detail_direct.asp?item_cde=A36095-043&item_rev=01&url_param=unused'  | 'Approved'    | 'YES' | '8'   | 'SMO_BOARDS'      | '56' 
'12.0pF'   | '50V'   | '5%'       | '0402LF'  | 'EMPTY'  | 'A36095-043'(!) = 'YES;YES;YES;UNK;ok;VLD'           | 'A36095-043'  | 'SMC0402A' | '(SMX0402,SMX0402A,SMX0402B)' | 'NA'       | '50V'         | '5%'       | 'DISCRETE' | 'CHIP0402'                                     | '0.024 IN' | 'CHIP0402'     | ''          | '1142' | 'http://speed.intel.com:8081/speed/module/pdm/item/pdm_item_detail_direct.asp?item_cde=A36095-043&item_rev=01&url_param=unused'  | 'Approved'    | 'YES' | '8'   | 'SMO_BOARDS'      | '56' 
'22.0pF'   | '50V'   | '5%'       | '0402LF'  | 'COG'    | 'A36095-030'(!) = 'YES;YES;YES;UNK;ok;CIP'           | 'A36095-030'  | 'SMC0402A' | '(SMX0402,SMX0402A,SMX0402B)' | '22.0pF'   | '50V'         | '5%'       | 'DISCRETE' | 'CHIP0402'                                     | '0.024 IN' | 'CHIP0402'     | ''          | '1142' | 'http://speed.intel.com:8081/speed/module/pdm/item/pdm_item_detail_direct.asp?item_cde=A36095-030&item_rev=01&url_param=unused'  | 'Approved'    | 'YES' | '12'  | 'SMO_BOARDS'      | '56' 
'22.0pF'   | '50V'   | '5%'       | '0402LF'  | 'EMPTY'  | 'A36095-030'(!) = 'YES;YES;YES;UNK;ok;CIP'           | 'A36095-030'  | 'SMC0402A' | '(SMX0402,SMX0402A,SMX0402B)' | 'NA'       | '50V'         | '5%'       | 'DISCRETE' | 'CHIP0402'                                     | '0.024 IN' | 'CHIP0402'     | ''          | '1142' | 'http://speed.intel.com:8081/speed/module/pdm/item/pdm_item_detail_direct.asp?item_cde=A36095-030&item_rev=01&url_param=unused'  | 'Approved'    | 'YES' | '12'  | 'SMO_BOARDS'      | '56' 
'33.0pF'   | '50V'   | '5%'       | '0402'    | 'EMPTY'  | 'A36095-031'(!) = 'YES;YES;YES;UNK;ok;CIP'           | 'A36095-031'  | 'SMC0402A' | '(SMX0402,SMX0402A,SMX0402B)' | 'NA'       | '50V'         | '5%'       | 'DISCRETE' | 'CHIP0402'                                     | '0.024 IN' | 'CHIP0402'     | ''          | '1142' | 'http://speed.intel.com:8081/speed/module/pdm/item/pdm_item_detail_direct.asp?item_cde=A36095-031&item_rev=01&url_param=unused'  | 'Approved'    | 'YES' | '11'  | 'SMO_BOARDS'      | '56' 
'33.0pF'   | '50V'   | '5%'       | '0402LF'  | 'EMPTY'  | 'A36095-031'(!) = 'YES;YES;YES;UNK;ok;CIP'           | 'A36095-031'  | 'SMC0402A' | '(SMX0402,SMX0402A,SMX0402B)' | 'NA'       | '50V'         | '5%'       | 'DISCRETE' | 'CHIP0402'                                     | '0.024 IN' | 'CHIP0402'     | ''          | '1142' | 'http://speed.intel.com:8081/speed/module/pdm/item/pdm_item_detail_direct.asp?item_cde=A36095-031&item_rev=01&url_param=unused'  | 'Approved'    | 'YES' | '11'  | 'SMO_BOARDS'      | '56' 
'33.0pF'   | '50V'   | '5%'       | '0402'    | 'COG'    | 'A36095-031'(!) = 'YES;YES;YES;UNK;ok;CIP'           | 'A36095-031'  | 'SMC0402A' | '(SMX0402,SMX0402A,SMX0402B)' | '33.0pF'   | '50V'         | '5%'       | 'DISCRETE' | 'CHIP0402'                                     | '0.024 IN' | 'CHIP0402'     | ''          | '1142' | 'http://speed.intel.com:8081/speed/module/pdm/item/pdm_item_detail_direct.asp?item_cde=A36095-031&item_rev=01&url_param=unused'  | 'Approved'    | 'YES' | '11'  | 'SMO_BOARDS'      | '56' 
'33.0pF'   | '50V'   | '5%'       | '0402LF'  | 'COG'    | 'A36095-031'(!) = 'YES;YES;YES;UNK;ok;CIP'           | 'A36095-031'  | 'SMC0402A' | '(SMX0402,SMX0402A,SMX0402B)' | '33.0pF'   | '50V'         | '5%'       | 'DISCRETE' | 'CHIP0402'                                     | '0.024 IN' | 'CHIP0402'     | ''          | '1142' | 'http://speed.intel.com:8081/speed/module/pdm/item/pdm_item_detail_direct.asp?item_cde=A36095-031&item_rev=01&url_param=unused'  | 'Approved'    | 'YES' | '11'  | 'SMO_BOARDS'      | '56' 
'15.0pF'   | '50V'   | '5%'       | '0402LF'  | 'EMPTY'  | 'A36095-047'(!) = 'YES;YES;YES;UNK;ok;VLD'           | 'A36095-047'  | 'SMC0402A' | '(SMX0402,SMX0402A,SMX0402B)' | 'NA'       | '50V'         | '5%'       | 'DISCRETE' | 'CHIP0402'                                     | '0.024 IN' | 'CHIP0402'     | ''          | '1142' | 'http://speed.intel.com:8081/speed/module/pdm/item/pdm_item_detail_direct.asp?item_cde=A36095-047&item_rev=01&url_param=unused'  | 'Approved'    | 'YES' | '13'  | 'SMO_BOARDS'      | '56' 
'15.0pF'   | '50V'   | '5%'       | '0402LF'  | 'COG'    | 'A36095-047'(!) = 'YES;YES;YES;UNK;ok;VLD'           | 'A36095-047'  | 'SMC0402A' | '(SMX0402,SMX0402A,SMX0402B)' | '15.0pF'   | '50V'         | '5%'       | 'DISCRETE' | 'CHIP0402'                                     | '0.024 IN' | 'CHIP0402'     | ''          | '1142' | 'http://speed.intel.com:8081/speed/module/pdm/item/pdm_item_detail_direct.asp?item_cde=A36095-047&item_rev=01&url_param=unused'  | 'Approved'    | 'YES' | '13'  | 'SMO_BOARDS'      | '56' 
'27.0pF'   | '50V'   | '5%'       | '0402LF'  | 'EMPTY'  | 'A36095-038'(!) = 'YES;YES;YES;UNK;ok;CIP'           | 'A36095-038'  | 'SMC0402A' | '(SMX0402,SMX0402A,SMX0402B)' | 'NA'       | '50V'         | '5%'       | 'DISCRETE' | 'CHIP0402'                                     | '0.022 IN' | 'CHIP0402'     | ''          | '1142' | 'http://speed.intel.com:8081/speed/module/pdm/item/pdm_item_detail_direct.asp?item_cde=A36095-038&item_rev=01&url_param=unused'  | 'Approved'    | 'YES' | '9'   | 'SMO_BOARDS'      | '56' 
'47.0pF'   | '50V'   | '5%'       | '0402LF'  | 'EMPTY'  | 'A36095-025'(!) = 'YES;YES;YES;UNK;ok;VLD'           | 'A36095-025'  | 'SMC0402A' | '(SMX0402,SMX0402A,SMX0402B)' | 'NA'       | '50V'         | '5%'       | 'DISCRETE' | 'CHIP0402'                                     | '0.034 IN' | 'CHIP0402'     | ''          | '1142' | 'http://speed.intel.com:8081/speed/module/pdm/item/pdm_item_detail_direct.asp?item_cde=A36095-025&item_rev=01&url_param=unused'  | 'Approved'    | 'YES' | '10'  | 'SMO_BOARDS'      | '56' 
'47.0pF'   | '50V'   | '5%'       | '0402LF'  | 'COG'    | 'A36095-025'(!) = 'YES;YES;YES;UNK;ok;VLD'           | 'A36095-025'  | 'SMC0402A' | '(SMX0402,SMX0402A,SMX0402B)' | '47.0pF'   | '50V'         | '5%'       | 'DISCRETE' | 'CHIP0402'                                     | '0.034 IN' | 'CHIP0402'     | ''          | '1142' | 'http://speed.intel.com:8081/speed/module/pdm/item/pdm_item_detail_direct.asp?item_cde=A36095-025&item_rev=01&url_param=unused'  | 'Approved'    | 'YES' | '10'  | 'SMO_BOARDS'      | '56' 
'27.0pF'   | '50V'   | '5%'       | '0402LF'  | 'COG'    | 'A36095-038'(!) = 'YES;YES;YES;UNK;ok;CIP'           | 'A36095-038'  | 'SMC0402A' | '(SMX0402,SMX0402A,SMX0402B)' | '27.0pF'   | '50V'         | '5%'       | 'DISCRETE' | 'CHIP0402'                                     | '0.022 IN' | 'CHIP0402'     | ''          | '1142' | 'http://speed.intel.com:8081/speed/module/pdm/item/pdm_item_detail_direct.asp?item_cde=A36095-038&item_rev=01&url_param=unused'  | 'Approved'    | 'YES' | '9'   | 'SMO_BOARDS'      | '56' 
'18pF'     | '50V'   | '5%'       | '0402LF'  | 'EMPTY'  | 'A36095-042'(!) = 'YES;YES;YES;UNK;ok;VLD'           | 'A36095-042'  | 'SMC0402A' | '(SMX0402,SMX0402A,SMX0402B)' | 'NA'       | '50V'         | '5%'       | 'DISCRETE' | 'CHIP0402'                                     | '0.022 IN' | 'CHIP0402'     | ''          | '1142' | 'http://speed.intel.com:8081/speed/module/pdm/item/pdm_item_detail_direct.asp?item_cde=A36095-042&item_rev=01&url_param=unused'  | 'Approved'    | 'YES' | '10'  | 'SMO_BOARDS'      | '56' 
'18pF'     | '50V'   | '5%'       | '0402LF'  | 'C0G'    | 'A36095-042'(!) = 'YES;YES;YES;UNK;ok;VLD'           | 'A36095-042'  | 'SMC0402A' | '(SMX0402,SMX0402A,SMX0402B)' | '18PF'     | '50V'         | '5%'       | 'DISCRETE' | 'CHIP0402'                                     | '0.022 IN' | 'CHIP0402'     | ''          | '1142' | 'http://speed.intel.com:8081/speed/module/pdm/item/pdm_item_detail_direct.asp?item_cde=A36095-042&item_rev=01&url_param=unused'  | 'Approved'    | 'YES' | '10'  | 'SMO_BOARDS'      | '56' 
'220pF'    | '50V'   | '10%'      | '0402LF'  | 'X7R'    | 'A36096-050'(!) = 'YES;YES;YES;UNK;ok;VLD'           | 'A36096-050'  | 'SMC0402A' | '(SMX0402,SMX0402A,SMX0402B)' | '220pF'    | '50V'         | '10%'      | 'DISCRETE' | 'CHIP0402'                                     | '0.024 IN' | 'CHIP0402'     | ''          | '1142' | 'http://speed.intel.com:8081/speed/module/pdm/item/pdm_item_detail_direct.asp?item_cde=A36096-050&item_rev=01&url_param=unused'  | 'Approved'    | 'YES' | '12'  | 'SMO_BOARDS'      | '56' 
'220pF'    | '50V'   | '10%'      | '0402LF'  | 'EMPTY'  | 'A36096-050'(!) = 'YES;YES;YES;UNK;ok;VLD'           | 'A36096-050'  | 'SMC0402A' | '(SMX0402,SMX0402A,SMX0402B)' | 'NA'       | '50V'         | '10%'      | 'DISCRETE' | 'CHIP0402'                                     | '0.024 IN' | 'CHIP0402'     | ''          | '1142' | 'http://speed.intel.com:8081/speed/module/pdm/item/pdm_item_detail_direct.asp?item_cde=A36096-050&item_rev=01&url_param=unused'  | 'Approved'    | 'YES' | '12'  | 'SMO_BOARDS'      | '56' 
'270pF'    | '50V'   | '10%'      | '0402LF'  | 'X7R'    | 'A36096-065'(!) = 'YES;YES;YES;UNK;ok;VLD'           | 'A36096-065'  | 'SMC0402A' | '(SMX0402,SMX0402A,SMX0402B)' | '270pF'    | '50V'         | '10%'      | 'DISCRETE' | 'CHIP0402'                                     | '0.024 IN' | 'CHIP0402'     | ''          | '1142' | 'http://speed.intel.com:8081/speed/module/pdm/item/pdm_item_detail_direct.asp?item_cde=A36096-065&item_rev=01&url_param=unused'  | 'Approved'    | 'NO'  | '7'   | 'SMO_BOARDS'      | '56' 
'270pF'    | '50V'   | '10%'      | '0402LF'  | 'EMPTY'  | 'A36096-065'(!) = 'YES;YES;YES;UNK;ok;VLD'           | 'A36096-065'  | 'SMC0402A' | '(SMX0402,SMX0402A,SMX0402B)' | 'NA'       | '50V'         | '10%'      | 'DISCRETE' | 'CHIP0402'                                     | '0.024 IN' | 'CHIP0402'     | ''          | '1142' | 'http://speed.intel.com:8081/speed/module/pdm/item/pdm_item_detail_direct.asp?item_cde=A36096-065&item_rev=01&url_param=unused'  | 'Approved'    | 'NO'  | '7'   | 'SMO_BOARDS'      | '56' 
'470pF'    | '50V'   | '10%'      | '0402LF'  | 'X7R'    | 'A36096-049'(!) = 'YES;YES;YES;UNK;ok;VLD'           | 'A36096-049'  | 'SMC0402A' | '(SMX0402,SMX0402A,SMX0402B)' | '470pF'    | '50V'         | '10%'      | 'DISCRETE' | 'CHIP0402'                                     | '0.024 IN' | 'CHIP0402'     | ''          | '1142' | 'http://speed.intel.com:8081/speed/module/pdm/item/pdm_item_detail_direct.asp?item_cde=A36096-049&item_rev=01&url_param=unused'  | 'Approved'    | 'YES' | '13'  | 'SMO_BOARDS'      | '56' 
'470pF'    | '50V'   | '10%'      | '0402LF'  | 'EMPTY'  | 'A36096-049'(!) = 'YES;YES;YES;UNK;ok;VLD'           | 'A36096-049'  | 'SMC0402A' | '(SMX0402,SMX0402A,SMX0402B)' | 'NA'       | '50V'         | '10%'      | 'DISCRETE' | 'CHIP0402'                                     | '0.024 IN' | 'CHIP0402'     | ''          | '1142' | 'http://speed.intel.com:8081/speed/module/pdm/item/pdm_item_detail_direct.asp?item_cde=A36096-049&item_rev=01&url_param=unused'  | 'Approved'    | 'YES' | '13'  | 'SMO_BOARDS'      | '56' 
'2200pF'   | '50V'   | '10%'      | '0402LF'  | 'X7R'    | 'A36096-075'(!) = 'YES;YES;YES;UNK;ok;CIP'           | 'A36096-075'  | 'SMC0402A' | '(SMX0402,SMX0402A,SMX0402B)' | '2200pF'   | '50V'         | '10%'      | 'DISCRETE' | 'CHIP0402'                                     | '0.024 IN' | 'CHIP0402'     | ''          | '1142' | 'http://speed.intel.com:8081/speed/module/pdm/item/pdm_item_detail_direct.asp?item_cde=A36096-075&item_rev=01&url_param=unused'  | 'Approved'    | 'NO'  | '7'   | 'SMO_BOARDS'      | '56' 
'2200pF'   | '50V'   | '10%'      | '0402LF'  | 'EMPTY'  | 'A36096-075'(!) = 'YES;YES;YES;UNK;ok;CIP'           | 'A36096-075'  | 'SMC0402A' | '(SMX0402,SMX0402A,SMX0402B)' | 'NA'       | '50V'         | '10%'      | 'DISCRETE' | 'CHIP0402'                                     | '0.024 IN' | 'CHIP0402'     | ''          | '1142' | 'http://speed.intel.com:8081/speed/module/pdm/item/pdm_item_detail_direct.asp?item_cde=A36096-075&item_rev=01&url_param=unused'  | 'Approved'    | 'NO'  | '7'   | 'SMO_BOARDS'      | '56' 
'3300pF'   | '50V'   | '10%'      | '0402LF'  | 'EMPTY'  | 'A36096-091'(!) = 'YES;YES;YES;UNK;ok;YTC'           | 'A36096-091'  | 'SMC0402A' | '(SMX0402,SMX0402A,SMX0402B)' | 'NA'       | '50V'         | '10%'      | 'DISCRETE' | 'CHIP0402'                                     | '0.022 IN' | 'CHIP0402'     | ''          | '1142' | 'http://speed.intel.com:8081/speed/module/pdm/item/pdm_item_detail_direct.asp?item_cde=A36096-091&item_rev=01&url_param=unused'  | 'Approved'    | 'YES' | '8'   | 'SMO_BOARDS'      | '56' 
'3300pF'   | '50V'   | '10%'      | '0402LF'  | 'X7R'    | 'A36096-091'(!) = 'YES;YES;YES;UNK;ok;YTC'           | 'A36096-091'  | 'SMC0402A' | '(SMX0402,SMX0402A,SMX0402B)' | '3300pF'   | '50V'         | '10%'      | 'DISCRETE' | 'CHIP0402'                                     | '0.022 IN' | 'CHIP0402'     | ''          | '1142' | 'http://speed.intel.com:8081/speed/module/pdm/item/pdm_item_detail_direct.asp?item_cde=A36096-091&item_rev=01&url_param=unused'  | 'Approved'    | 'YES' | '8'   | 'SMO_BOARDS'      | '56' 
'4700pF'   | '50V'   | '10%'      | '0402LF'  | 'X7R'    | 'A36096-066'(!) = 'YES;YES;YES;UNK;ok;CIP'           | 'A36096-066'  | 'SMC0402A' | '(SMX0402,SMX0402A,SMX0402B)' | '4700pF'   | '50V'         | '10%'      | 'DISCRETE' | 'CHIP0402'                                     | '0.024 IN' | 'CHIP0402'     | ''          | '1142' | 'http://speed.intel.com:8081/speed/module/pdm/item/pdm_item_detail_direct.asp?item_cde=A36096-066&item_rev=01&url_param=unused'  | 'Approved'    | 'NO'  | '7'   | 'SMO_BOARDS'      | '56' 
'4700pF'   | '50V'   | '10%'      | '0402LF'  | 'EMPTY'  | 'A36096-066'(!) = 'YES;YES;YES;UNK;ok;CIP'           | 'A36096-066'  | 'SMC0402A' | '(SMX0402,SMX0402A,SMX0402B)' | 'NA'       | '50V'         | '10%'      | 'DISCRETE' | 'CHIP0402'                                     | '0.024 IN' | 'CHIP0402'     | ''          | '1142' | 'http://speed.intel.com:8081/speed/module/pdm/item/pdm_item_detail_direct.asp?item_cde=A36096-066&item_rev=01&url_param=unused'  | 'Approved'    | 'NO'  | '7'   | 'SMO_BOARDS'      | '56' 
'10uF'     | '6.3V'  | '20%'      | '0603'    | 'X6S'    | 'E15431-002'(!) = 'YES;YES;YES;UNK;ok;VLD'           | 'E15431-002'  | 'SMC0603A' | '(SMX0603)'                   | '10uF'     | '6.3V'        | '20%'      | 'DISCRETE' | 'CHIP0603'                                     | '0.039 IN' | 'CHIP0603'     | ''          | '443'  | 'http://speed.intel.com:8081/speed/module/pdm/item/pdm_item_detail_direct.asp?item_cde=E15431-002&item_rev=01&url_param=unused'  | 'Conditional' | 'NO'  | '2'   | 'SMO_BOARDS'      | '56' 
'10uF'     | '4V'    | '20%'      | '0603LF'  | 'EMPTY'  | 'E15431-001'(!) = 'YES;YES;YES;UNK;ok;VLD'           | 'E15431-001'  | 'SMC0603A' | '(SMX0603)'                   | 'NA'       | '4V'          | '20%'      | 'DISCRETE' | 'CHIP0603'                                     | '0.037 IN' | 'CHIP0603'     | ''          | '443'  | 'http://speed.intel.com:8081/speed/module/pdm/item/pdm_item_detail_direct.asp?item_cde=E15431-001&item_rev=01&url_param=unused'  | 'Conditional' | 'NO'  | '3'   | 'SMO_BOARDS'      | '???'
'10uF'     | '4V'    | '20%'      | '0603LF'  | 'X6S'    | 'E15431-001'(!) = 'YES;YES;YES;UNK;ok;VLD'           | 'E15431-001'  | 'SMC0603A' | '(SMX0603)'                   | '10uF'     | '4V'          | '20%'      | 'DISCRETE' | 'CHIP0603'                                     | '0.027 IN' | 'CHIP0603'     | ''          | '443'  | 'http://speed.intel.com:8081/speed/module/pdm/item/pdm_item_detail_direct.asp?item_cde=E15431-001&item_rev=01&url_param=unused'  | 'Conditional' | 'NO'  | '3'   | 'SMO_BOARDS'      | '???'
'10uF'     | '6.3V'  | '20%'      | '0603'    | 'EMPTY'  | 'E15431-002'(!) = 'YES;YES;YES;UNK;ok;VLD'           | 'E15431-002'  | 'SMC0603A' | '(SMX0603)'                   | 'NA'       | '6.3V'        | '20%'      | 'DISCRETE' | 'CHIP0603'                                     | '0.039 IN' | 'CHIP0603'     | ''          | '443'  | 'http://speed.intel.com:8081/speed/module/pdm/item/pdm_item_detail_direct.asp?item_cde=E15431-002&item_rev=01&url_param=unused'  | 'Conditional' | 'NO'  | '2'   | 'SMO_BOARDS'      | '56' 
'0.033uF'  | '50V'   | '10%'      | '0603LF'  | 'EMPTY'  | '603269-064'(!) = 'YES;YES;UNK;UNK;ok;VLD'           | '603269-064'  | 'SMC0603A' | '(SMX0603)'                   | 'NA'       | '50V'         | '10%'      | 'DISCRETE' | 'CHIP0603'                                     | '0.035 IN' | 'CHIP0603'     | ''          | '443'  | 'http://speed.intel.com:8081/speed/module/pdm/item/pdm_item_detail_direct.asp?item_cde=603269-064&item_rev=01&url_param=unused'  | 'Approved'    | 'YES' | '8'   | 'SMO_BOARDS'      | '56' 
'0.033uF'  | '50V'   | '10%'      | '0603LF'  | 'X7R'    | '603269-064'(!) = 'YES;YES;UNK;UNK;ok;VLD'           | '603269-064'  | 'SMC0603A' | '(SMX0603)'                   | '0.033uF'  | '50V'         | '10%'      | 'DISCRETE' | 'CHIP0603'                                     | '0.035 IN' | 'CHIP0603'     | ''          | '443'  | 'http://speed.intel.com:8081/speed/module/pdm/item/pdm_item_detail_direct.asp?item_cde=603269-064&item_rev=01&url_param=unused'  | 'Approved'    | 'YES' | '8'   | 'SMO_BOARDS'      | '56' 
'0.1uF'    | '25V'   | '10%'      | '0603LF'  | 'X7R'    | '602433-020'(!) = 'YES;YES;YES;UNK;ok;VLD'           | '602433-020'  | 'SMC0603A' | '(SMX0603)'                   | '0.1uF'    | '25V'         | '10%'      | 'DISCRETE' | 'CHIP0603'                                     | '0.035 IN' | 'CHIP0603'     | ''          | '443'  | 'http://speed.intel.com:8081/speed/module/pdm/item/pdm_item_detail_direct.asp?item_cde=602433-020&item_rev=01&url_param=unused'  | 'Conditional' | 'YES' | '9'   | 'SMO_BOARDS'      | '56' 
'0.1uF'    | '25V'   | '10%'      | '0603LF'  | 'EMPTY'  | '602433-020'(!) = 'YES;YES;YES;UNK;ok;VLD'           | '602433-020'  | 'SMC0603A' | '(SMX0603)'                   | 'NA'       | '25V'         | '10%'      | 'DISCRETE' | 'CHIP0603'                                     | '0.035 IN' | 'CHIP0603'     | ''          | '443'  | 'http://speed.intel.com:8081/speed/module/pdm/item/pdm_item_detail_direct.asp?item_cde=602433-020&item_rev=01&url_param=unused'  | 'Conditional' | 'YES' | '9'   | 'SMO_BOARDS'      | '56' 
'0.47uF'   | '16V'   | '10%'      | '0603'    | 'X7R'    | '202297-006'(!) = 'YES;YES;YES;UNK;ok;VLD'           | '202297-006'  | 'SMC0603A' | '(SMX0603)'                   | '0.47uF'   | '16V'         | '10%'      | 'DISCRETE' | 'CAPC,X7R,0603,0.470UF,16.000V,+/- 10%'        | '0.035 IN' | 'CHIP0603'     | ''          | '443'  | 'http://speed.intel.com:8081/speed/module/pdm/item/pdm_item_detail_direct.asp?item_cde=202297-006&item_rev=01&url_param=unused'  | 'Conditional' | 'NO'  | '7'   | 'SMO_BOARDS'      | '56' 
'0.47uF'   | '16V'   | '10%'      | '0603'    | 'EMPTY'  | '202297-006'(!) = 'YES;YES;YES;UNK;ok;VLD'           | '202297-006'  | 'SMC0603A' | '(SMX0603)'                   | 'NA'       | '16V'         | '10%'      | 'DISCRETE' | 'CAPC,X7R,0603,0.470UF,16.000V,+/- 10%'        | '0.035 IN' | 'CHIP0603'     | ''          | '443'  | 'http://speed.intel.com:8081/speed/module/pdm/item/pdm_item_detail_direct.asp?item_cde=202297-006&item_rev=01&url_param=unused'  | 'Conditional' | 'NO'  | '7'   | 'SMO_BOARDS'      | '56' 
'4.7uF'    | '6.3V'  | '10%'      | '0603'    | 'X6S'    | 'E15431-003'(!) = 'YES;YES;YES;UNK;ok;VLD'           | 'E15431-003'  | 'SMC0603A' | '(SMX0603)'                   | '4.7uF'    | '6.3V'        | '10%'      | 'DISCRETE' | 'CHIP0603'                                     | '0.035 IN' | 'CHIP0603'     | ''          | '443'  | 'http://speed.intel.com:8081/speed/module/pdm/item/pdm_item_detail_direct.asp?item_cde=E15431-003&item_rev=01&url_param=unused'  | 'Conditional' | 'NO'  | '5'   | 'SMO_BOARDS'      | '???'
'4.7uF'    | '6.3V'  | '10%'      | '0603'    | 'EMPTY'  | 'E15431-003'(!) = 'YES;YES;YES;UNK;ok;VLD'           | 'E15431-003'  | 'SMC0603A' | '(SMX0603)'                   | 'NA'       | '6.3V'        | '10%'      | 'DISCRETE' | 'CHIP0603'                                     | '0.035 IN' | 'CHIP0603'     | ''          | '443'  | 'http://speed.intel.com:8081/speed/module/pdm/item/pdm_item_detail_direct.asp?item_cde=E15431-003&item_rev=01&url_param=unused'  | 'Conditional' | 'NO'  | '5'   | 'SMO_BOARDS'      | '???'
'22.0uF'   | '4V'    | '20%'      | '0603'    | 'EMPTY'  | 'E15431-004'(!) = 'YES;YES;YES;UNK;ok;VLD'           | 'E15431-004'  | 'SMC0603A' | '(SMX0603)'                   | 'NA'       | '4V'          | '20%'      | 'DISCRETE' | 'CAPC,X6S,0603,22.00UF,4.00V,+/- 20%'          | '0.035 IN' | 'CHIP0603'     | ''          | '443'  | 'http://speed.intel.com:8081/speed/module/pdm/item/pdm_item_detail_direct.asp?item_cde=E15431-004&item_rev=01&url_param=unused'  | 'Design'      | 'NO'  | '2'   | 'SMO_BOARDS'      | '???'
'22.0uF'   | '4V'    | '20%'      | '0603'    | 'X6S'    | 'E15431-004'(!) = 'YES;YES;YES;UNK;ok;VLD'           | 'E15431-004'  | 'SMC0603A' | '(SMX0603)'                   | '22.0uF'   | '4V'          | '20%'      | 'DISCRETE' | 'CAPC,X6S,0603,22.00UF,4.00V,+/- 20%'          | '0.035 IN' | 'CHIP0603'     | ''          | '443'  | 'http://speed.intel.com:8081/speed/module/pdm/item/pdm_item_detail_direct.asp?item_cde=E15431-004&item_rev=01&url_param=unused'  | 'Design'      | 'NO'  | '2'   | 'SMO_BOARDS'      | '???'
'47uF'     | '4V'    | '20%'      | '0603'    | 'EMPTY'  | '602433-106'(!) = ''                                 | '602433-106'  | 'SMC0603C' | ''                            | 'NA'       | '4V'          | '20%'      | 'DISCRETE' | 'CAPC,X5R,0603,47.00UF,4.00V,+/- 20%'          | '0.039 IN' | 'CHIP0603'     | ''          | '3802' | 'http://speed.intel.com:8081/speed/module/pdm/item/pdm_item_detail_direct.asp?item_cde=602433-106&item_rev=01&url_param=unused'  | ''            | ''    | ''    | ''                | ''   
'47uF'     | '4V'    | '20%'      | '0603'    | 'X5R'    | '602433-106'(!) = ''                                 | '602433-106'  | 'SMC0603C' | ''                            | '47uF'     | '4V'          | '20%'      | 'DISCRETE' | 'CAPC,X5R,0603,47.00UF,4.00V,+/- 20%'          | '0.039 IN' | 'CHIP0603'     | ''          | '3802' | 'http://speed.intel.com:8081/speed/module/pdm/item/pdm_item_detail_direct.asp?item_cde=602433-106&item_rev=01&url_param=unused'  | ''            | ''    | ''    | ''                | ''   
'100uF'    | '4V'    | '20%'      | '0805'    | 'EMPTY'  | '602433-112'(!) = ''                                 | '602433-112'  | 'SMC0805A' | '(SMX0805)'                   | 'NA'       | '4V'          | '20%'      | 'DISCRETE' | 'CAPC,X5R,0805,100.00UF,4.00V,+/- 20%'         | '0.057 IN' | 'CHIP0805'     | ''          | '445'  | 'http://speed.intel.com:8081/speed/module/pdm/item/pdm_item_detail_direct.asp?item_cde=602433-112&item_rev=01&url_param=unused'  | ''            | ''    | ''    | ''                | ''   
'100uF'    | '4V'    | '20%'      | '0805'    | 'X5R'    | '602433-112'(!) = ''                                 | '602433-112'  | 'SMC0805A' | '(SMX0805)'                   | '100uF'    | '4V'          | '20%'      | 'DISCRETE' | 'CAPC,X5R,0805,100.00UF,4.00V,+/- 20%'         | '0.057 IN' | 'CHIP0805'     | ''          | '445'  | 'http://speed.intel.com:8081/speed/module/pdm/item/pdm_item_detail_direct.asp?item_cde=602433-112&item_rev=01&url_param=unused'  | ''            | ''    | ''    | ''                | ''   
'10uF'     | '16V'   | '10%'      | '0805'    | 'X7R'    | 'G10601-001'(!) = 'YES;YES;YES;UNK;ok;VLD'           | 'G10601-001'  | 'SMC0805A' | '(SMX0805)'                   | '10uF'     | '16V'         | '10%'      | 'DISCRETE' | 'CHIP0805'                                     | '0.049 IN' | 'CHIP0805'     | ''          | '445'  | 'http://speed.intel.com:8081/speed/module/pdm/item/pdm_item_detail_direct.asp?item_cde=G10601-001&item_rev=01&url_param=unused'  | 'Design'      | 'NO'  | '2'   | 'SMO_BOARDS'      | '???'
'10uF'     | '16V'   | '10%'      | '0805'    | 'EMPTY'  | 'G10601-001'(!) = 'YES;YES;YES;UNK;ok;VLD'           | 'G10601-001'  | 'SMC0805A' | '(SMX0805)'                   | 'NA'       | '16V'         | '10%'      | 'DISCRETE' | 'CHIP0805'                                     | '0.049 IN' | 'CHIP0805'     | ''          | '445'  | 'http://speed.intel.com:8081/speed/module/pdm/item/pdm_item_detail_direct.asp?item_cde=G10601-001&item_rev=01&url_param=unused'  | 'Design'      | 'NO'  | '2'   | 'SMO_BOARDS'      | '???'
'10uF'     | '16V'   | '10%'      | '0805'    | 'X6S'    | 'C95333-007'(!) = 'YES;YES;YES;UNK;ok;VLD'           | 'C95333-007'  | 'SMC0805A' | '(SMX0805)'                   | '10uF'     | '16V'         | '10%'      | 'DISCRETE' | 'CHIP0805'                                     | '0.049 IN' | 'CHIP0805'     | ''          | '445'  | 'http://speed.intel.com:8081/speed/module/pdm/item/pdm_item_detail_direct.asp?item_cde=C95333-007&item_rev=01&url_param=unused'  | 'Conditional' | 'NO'  | '3'   | 'SMO_BOARDS'      | '???'
'10uF'     | '16V'   | '10%'      | '0805'    | 'EMPTY'  | 'C95333-007'(!) = 'YES;YES;YES;UNK;ok;VLD'           | 'C95333-007'  | 'SMC0805A' | '(SMX0805)'                   | 'NA'       | '16V'         | '10%'      | 'DISCRETE' | 'CHIP0805'                                     | '0.049 IN' | 'CHIP0805'     | ''          | '445'  | 'http://speed.intel.com:8081/speed/module/pdm/item/pdm_item_detail_direct.asp?item_cde=C95333-007&item_rev=01&url_param=unused'  | 'Conditional' | 'NO'  | '3'   | 'SMO_BOARDS'      | '???'
'22uF'     | '4V'    | '20%'      | '0805LF'  | 'X6S'    | 'C95333-002'(!) = 'YES;YES;YES;UNK;ok;VLD'           | 'C95333-002'  | 'SMC0805A' | '(SMX0805)'                   | '22uF'     | '4V'          | '20%'      | 'DISCRETE' | 'CHIP0805'                                     | '0.055 IN' | 'CHIP0805'     | ''          | '445'  | 'http://speed.intel.com:8081/speed/module/pdm/item/pdm_item_detail_direct.asp?item_cde=C95333-002&item_rev=01&url_param=unused'  | 'Conditional' | 'NO'  | '4'   | 'SMO_BOARDS'      | '56' 
'22uF'     | '4V'    | '20%'      | '0805LF'  | 'EMPTY'  | 'C95333-002'(!) = 'YES;YES;YES;UNK;ok;VLD'           | 'C95333-002'  | 'SMC0805A' | '(SMX0805)'                   | 'NA'       | '4V'          | '20%'      | 'DISCRETE' | 'CHIP0805'                                     | '0.055 IN' | 'CHIP0805'     | ''          | '445'  | 'http://speed.intel.com:8081/speed/module/pdm/item/pdm_item_detail_direct.asp?item_cde=C95333-002&item_rev=01&url_param=unused'  | 'Conditional' | 'NO'  | '4'   | 'SMO_BOARDS'      | '56' 
'22uF'     | '6.3V'  | '20%'      | '0805'    | 'X6S'    | 'C95333-008'(!) = 'YES;YES;YES;UNK;ok;VLD'           | 'C95333-008'  | 'SMC0805A' | '(SMX0805)'                   | '22uF'     | '6.3V'        | '20%'      | 'DISCRETE' | 'CHIP0805'                                     | '0.055 IN' | 'CHIP0805'     | ''          | '445'  | 'http://speed.intel.com:8081/speed/module/pdm/item/pdm_item_detail_direct.asp?item_cde=C95333-008&item_rev=01&url_param=unused'  | 'Conditional' | 'YES' | '5'   | 'SMO_BOARDS'      | '???'
'22uF'     | '6.3V'  | '20%'      | '0805'    | 'EMPTY'  | 'C95333-008'(!) = 'YES;YES;YES;UNK;ok;VLD'           | 'C95333-008'  | 'SMC0805A' | '(SMX0805)'                   | 'NA'       | '6.3V'        | '20%'      | 'DISCRETE' | 'CHIP0805'                                     | '0.055 IN' | 'CHIP0805'     | ''          | '445'  | 'http://speed.intel.com:8081/speed/module/pdm/item/pdm_item_detail_direct.asp?item_cde=C95333-008&item_rev=01&url_param=unused'  | 'Conditional' | 'YES' | '5'   | 'SMO_BOARDS'      | '???'
'47uF'     | '4V'    | '20%'      | '0805'    | 'X6S'    | 'C95333-006'(!) = 'YES;YES;YES;UNK;ok;VLD'           | 'C95333-006'  | 'SMC0805A' | '(SMX0805)'                   | '47uF'     | '4V'          | '20%'      | 'DISCRETE' | 'CHIP0805'                                     | '0.060 IN' | 'CHIP0805'     | ''          | '445'  | 'http://speed.intel.com:8081/speed/module/pdm/item/pdm_item_detail_direct.asp?item_cde=C95333-006&item_rev=01&url_param=unused'  | 'Conditional' | 'NO'  | '7'   | 'SMO_BOARDS'      | '???'
'47uF'     | '4V'    | '20%'      | '0805'    | 'EMPTY'  | 'C95333-006'(!) = 'YES;YES;YES;UNK;ok;VLD'           | 'C95333-006'  | 'SMC0805A' | '(SMX0805)'                   | 'NA'       | '4V'          | '20%'      | 'DISCRETE' | 'CHIP0805'                                     | '0.060 IN' | 'CHIP0805'     | ''          | '445'  | 'http://speed.intel.com:8081/speed/module/pdm/item/pdm_item_detail_direct.asp?item_cde=C95333-006&item_rev=01&url_param=unused'  | 'Conditional' | 'NO'  | '7'   | 'SMO_BOARDS'      | '???'
'0.068uF'  | '50V'   | '20%'      | '1206'    | 'EMPTY'  | '108427-047'(!) = 'YES;YES;UNK;UNK;ok;VLD'           | '108427-047'  | 'SMC1206A' | '(SMC1206AW)'                 | 'NA'       | '50V'         | '20%'      | 'DISCRETE' | 'CHIP1206'                                     | '0.038 IN' | 'CHIP'         | ''          | '447'  | 'http://speed.intel.com:8081/speed/module/pdm/item/pdm_item_detail_direct.asp?item_cde=108427-047&item_rev=01&url_param=unused'  | 'Archive'     | 'NO'  | '11'  | 'SMO_BOARDS'      | '56' 
'0.068uF'  | '50V'   | '20%'      | '1206'    | 'X7R'    | '108427-047'(!) = 'YES;YES;UNK;UNK;ok;VLD'           | '108427-047'  | 'SMC1206A' | '(SMC1206AW)'                 | '.068uF'   | '50V'         | '20%'      | 'DISCRETE' | 'CHIP1206'                                     | '0.038 IN' | 'CHIP'         | ''          | '447'  | 'http://speed.intel.com:8081/speed/module/pdm/item/pdm_item_detail_direct.asp?item_cde=108427-047&item_rev=01&url_param=unused'  | 'Archive'     | 'NO'  | '11'  | 'SMO_BOARDS'      | '56' 
'22uF'     | '16V'   | '10%'      | '1206LF'  | 'X6S'    | 'D38464-005'(!) = 'YES;YES;YES;UNK;ok;VLD'           | 'D38464-005'  | 'SMC1206A' | '(SMC1206AW)'                 | '22uF'     | '16V'         | '10%'      | 'DISCRETE' | 'CHIP1206'                                     | '0.071 IN' | 'CHIP'         | ''          | '447'  | 'http://speed.intel.com:8081/speed/module/pdm/item/pdm_item_detail_direct.asp?item_cde=D38464-005&item_rev=01&url_param=unused'  | 'Conditional' | 'NO'  | '1'   | 'SMO_BOARDS'      | '???'
'22uF'     | '16V'   | '10%'      | '1206LF'  | 'EMPTY'  | 'D38464-005'(!) = 'YES;YES;YES;UNK;ok;VLD'           | 'D38464-005'  | 'SMC1206A' | '(SMC1206AW)'                 | 'NA'       | '16V'         | '10%'      | 'DISCRETE' | 'CHIP1206'                                     | '0.071 IN' | 'CHIP'         | ''          | '447'  | 'http://speed.intel.com:8081/speed/module/pdm/item/pdm_item_detail_direct.asp?item_cde=D38464-005&item_rev=01&url_param=unused'  | 'Conditional' | 'NO'  | '1'   | 'SMO_BOARDS'      | '???'
'100uF'    | '16V'   | '20%'      | '1210'    | 'EMPTY'  | '644066-127'(!) = 'YES;YES;YES;UNK;ok;VLD'           | '644066-127'  | 'SMC1210A' | ''                            | 'NA'       | '16V'         | '20%'      | 'DISCRETE' | 'CAPC,X5R,1210,100.00UF,16.00V,+/- 20%'        | '0.110 IN' | 'CHIP'         | ''          | '449'  | 'http://speed.intel.com:8081/speed/module/pdm/item/pdm_item_detail_direct.asp?item_cde=644066-127&item_rev=01&url_param=unused'  | 'Design'      | 'NO'  | '1'   | 'SMO_BOARDS'      | '???'
'100uF'    | '16V'   | '20%'      | '1210'    | 'X5R'    | '644066-127'(!) = 'YES;YES;YES;UNK;ok;VLD'           | '644066-127'  | 'SMC1210A' | ''                            | '100uF'    | '16V'         | '20%'      | 'DISCRETE' | 'CAPC,X5R,1210,100.00UF,16.00V,+/- 20%'        | '0.110 IN' | 'CHIP'         | ''          | '449'  | 'http://speed.intel.com:8081/speed/module/pdm/item/pdm_item_detail_direct.asp?item_cde=644066-127&item_rev=01&url_param=unused'  | 'Design'      | 'NO'  | '1'   | 'SMO_BOARDS'      | '???'
'47uF'     | '16V'   | '20%'      | '1210'    | 'X6S'    | 'D38464-007'(!) = 'YES;YES;YES;UNK;ok;VLD'           | 'D38464-007'  | 'SMC1210A' | ''                            | '47uF'     | '16V'         | '20%'      | 'DISCRETE' | 'CHIP'                                         | '0.106 IN' | 'CHIP'         | ''          | '449'  | 'http://speed.intel.com:8081/speed/module/pdm/item/pdm_item_detail_direct.asp?item_cde=D38464-007&item_rev=01&url_param=unused'  | 'Design'      | 'N/A' | '1'   | 'SMO_BOARDS'      | '???'
'47uF'     | '16V'   | '20%'      | '1210'    | 'EMPTY'  | 'D38464-007'(!) = 'YES;YES;YES;UNK;ok;VLD'           | 'D38464-007'  | 'SMC1210A' | ''                            | 'NA'       | '16V'         | '20%'      | 'DISCRETE' | 'CHIP'                                         | '0.106 IN' | 'CHIP'         | ''          | '449'  | 'http://speed.intel.com:8081/speed/module/pdm/item/pdm_item_detail_direct.asp?item_cde=D38464-007&item_rev=01&url_param=unused'  | 'Design'      | 'N/A' | '1'   | 'SMO_BOARDS'      | '???'
END_PART
END.
